(kicad_pcb
	(version 20260206)
	(generator "pcbnew")
	(generator_version "10.0")
	(general
		(thickness 1.6)
		(legacy_teardrops no)
	)
	(paper "A4")
	(title_block
		(title "03242023_DA0F0TMBIJ0_F0T_Motherboard_J_brd_V01_OCP.brd")
		(comment 1 "Grand Teton / footprints 604-609 of 6105")
	)
	(layers
		(0 "F.Cu" signal "TOP")
		(4 "In1.Cu" signal "GND")
		(6 "In2.Cu" signal "IN1")
		(8 "In3.Cu" signal "GND1")
		(10 "In4.Cu" signal "IN2")
		(12 "In5.Cu" signal "GND2")
		(14 "In6.Cu" signal "IN3")
		(16 "In7.Cu" signal "GND3")
		(18 "In8.Cu" signal "VCC")
		(20 "In9.Cu" signal "VCC1")
		(22 "In10.Cu" signal "GND4")
		(24 "In11.Cu" signal "IN4")
		(26 "In12.Cu" signal "GND5")
		(28 "In13.Cu" signal "IN5")
		(30 "In14.Cu" signal "GND6")
		(32 "In15.Cu" signal "IN6")
		(34 "In16.Cu" signal "GND7")
		(2 "B.Cu" signal "BOTTOM")
		(9 "F.Adhes" user "F.Adhesive")
		(11 "B.Adhes" user "B.Adhesive")
		(13 "F.Paste" user "Package Geometry/Pastemask Top")
		(15 "B.Paste" user "Package Geometry/Pastemask Bottom")
		(5 "F.SilkS" user "Ref Des/Silkscreen Top")
		(7 "B.SilkS" user "Ref Des/Silkscreen Bottom")
		(1 "F.Mask" user "Board Geometry/Soldermask Top")
		(3 "B.Mask" user "Board Geometry/Soldermask Bottom")
		(17 "Dwgs.User" user "User.Drawings")
		(19 "Cmts.User" user "User.Comments")
		(21 "Eco1.User" user "User.Eco1")
		(23 "Eco2.User" user "User.Eco2")
		(25 "Edge.Cuts" user "Board Geometry/Outline")
		(27 "Margin" user)
		(31 "F.CrtYd" user "Package Geometry/Place Bound Top")
		(29 "B.CrtYd" user "Package Geometry/Place Bound Bottom")
		(35 "F.Fab" user "Ref Des/Assembly Top")
		(33 "B.Fab" user "Ref Des/Assembly Bottom")
	)
	(footprint ""
		(layer "F.Cu")
		(at 354.270818 -244.03177 90)
		(property "Reference" "C1003"
			(at 0 0 90)
			(layer "F.SilkS")
			(hide yes)
			(effects
				(font
					(size 1.27 1.27)
				)
			)
		)
		(property "Value" ""
			(at 0 0 90)
			(layer "F.Fab")
			(effects
				(font
					(size 1.27 1.27)
				)
			)
		)
		(duplicate_pad_numbers_are_jumpers no)
		(fp_line
			(start 0.7874 -0.4064)
			(end 0.7874 0.4064)
			(stroke
				(width 0.1524)
				(type default)
			)
			(layer "F.SilkS")
		)
		(fp_line
			(start -0.7874 -0.4064)
			(end 0.7874 -0.4064)
			(stroke
				(width 0.1524)
				(type default)
			)
			(layer "F.SilkS")
		)
		(fp_line
			(start 0.7874 0.4064)
			(end -0.7874 0.4064)
			(stroke
				(width 0.1524)
				(type default)
			)
			(layer "F.SilkS")
		)
		(fp_line
			(start -0.7874 0.4064)
			(end -0.7874 -0.4064)
			(stroke
				(width 0.1524)
				(type default)
			)
			(layer "F.SilkS")
		)
		(fp_line
			(start -0.12065 -0.305054)
			(end -0.12065 -0.2794)
			(stroke
				(width 0.1)
				(type default)
			)
			(layer "F.Fab")
		)
		(fp_line
			(start -0.67945 -0.305054)
			(end -0.12065 -0.305054)
			(stroke
				(width 0.1)
				(type default)
			)
			(layer "F.Fab")
		)
		(fp_line
			(start 0.67945 -0.3048)
			(end 0.67945 0.3048)
			(stroke
				(width 0.1)
				(type default)
			)
			(layer "F.Fab")
		)
		(fp_line
			(start 0.12065 -0.3048)
			(end 0.67945 -0.3048)
			(stroke
				(width 0.1)
				(type default)
			)
			(layer "F.Fab")
		)
		(fp_line
			(start 0.12065 -0.2794)
			(end 0.12065 -0.3048)
			(stroke
				(width 0.1)
				(type default)
			)
			(layer "F.Fab")
		)
		(fp_line
			(start -0.12065 -0.2794)
			(end 0.12065 -0.2794)
			(stroke
				(width 0.1)
				(type default)
			)
			(layer "F.Fab")
		)
		(fp_line
			(start 0.120396 0.2794)
			(end -0.12065 0.2794)
			(stroke
				(width 0.1)
				(type default)
			)
			(layer "F.Fab")
		)
		(fp_line
			(start -0.12065 0.2794)
			(end -0.12065 0.3048)
			(stroke
				(width 0.1)
				(type default)
			)
			(layer "F.Fab")
		)
		(fp_line
			(start 0.67945 0.3048)
			(end 0.120396 0.3048)
			(stroke
				(width 0.1)
				(type default)
			)
			(layer "F.Fab")
		)
		(fp_line
			(start 0.120396 0.3048)
			(end 0.120396 0.2794)
			(stroke
				(width 0.1)
				(type default)
			)
			(layer "F.Fab")
		)
		(fp_line
			(start -0.12065 0.3048)
			(end -0.67945 0.3048)
			(stroke
				(width 0.1)
				(type default)
			)
			(layer "F.Fab")
		)
		(fp_line
			(start -0.67945 0.3048)
			(end -0.67945 -0.305054)
			(stroke
				(width 0.1)
				(type default)
			)
			(layer "F.Fab")
		)
		(pad "1" smd circle
			(at -0.40005 0 90)
			(size 0 0)
			(layers "F.Cu" "F.Mask" "F.Paste")
			(net "PVCCIN_CPU0")
		)
		(pad "2" smd circle
			(at 0.40005 0 90)
			(size 0 0)
			(layers "F.Cu" "F.Mask" "F.Paste")
			(net "GND")
		)
	)
	(footprint ""
		(layer "F.Cu")
		(at 79.666084 -347.930978)
		(property "Reference" "PR286"
			(at 0 0 0)
			(layer "F.SilkS")
			(hide yes)
			(effects
				(font
					(size 1.27 1.27)
				)
			)
		)
		(property "Value" ""
			(at 0 0 0)
			(layer "F.Fab")
			(effects
				(font
					(size 1.27 1.27)
				)
			)
		)
		(duplicate_pad_numbers_are_jumpers no)
		(fp_line
			(start -0.7874 -0.4064)
			(end 0.7874 -0.4064)
			(stroke
				(width 0.1524)
				(type default)
			)
			(layer "F.SilkS")
		)
		(fp_line
			(start -0.7874 0.4064)
			(end -0.7874 -0.4064)
			(stroke
				(width 0.1524)
				(type default)
			)
			(layer "F.SilkS")
		)
		(fp_line
			(start 0.7874 -0.4064)
			(end 0.7874 0.4064)
			(stroke
				(width 0.1524)
				(type default)
			)
			(layer "F.SilkS")
		)
		(fp_line
			(start 0.7874 0.4064)
			(end -0.7874 0.4064)
			(stroke
				(width 0.1524)
				(type default)
			)
			(layer "F.SilkS")
		)
		(fp_line
			(start -0.67945 -0.305054)
			(end -0.12065 -0.305054)
			(stroke
				(width 0.1)
				(type default)
			)
			(layer "F.Fab")
		)
		(fp_line
			(start -0.67945 0.3048)
			(end -0.67945 -0.305054)
			(stroke
				(width 0.1)
				(type default)
			)
			(layer "F.Fab")
		)
		(fp_line
			(start -0.12065 -0.305054)
			(end -0.12065 -0.2794)
			(stroke
				(width 0.1)
				(type default)
			)
			(layer "F.Fab")
		)
		(fp_line
			(start -0.12065 -0.2794)
			(end 0.12065 -0.2794)
			(stroke
				(width 0.1)
				(type default)
			)
			(layer "F.Fab")
		)
		(fp_line
			(start -0.12065 0.2794)
			(end -0.12065 0.3048)
			(stroke
				(width 0.1)
				(type default)
			)
			(layer "F.Fab")
		)
		(fp_line
			(start -0.12065 0.3048)
			(end -0.67945 0.3048)
			(stroke
				(width 0.1)
				(type default)
			)
			(layer "F.Fab")
		)
		(fp_line
			(start 0.120396 0.2794)
			(end -0.12065 0.2794)
			(stroke
				(width 0.1)
				(type default)
			)
			(layer "F.Fab")
		)
		(fp_line
			(start 0.120396 0.3048)
			(end 0.120396 0.2794)
			(stroke
				(width 0.1)
				(type default)
			)
			(layer "F.Fab")
		)
		(fp_line
			(start 0.12065 -0.3048)
			(end 0.67945 -0.3048)
			(stroke
				(width 0.1)
				(type default)
			)
			(layer "F.Fab")
		)
		(fp_line
			(start 0.12065 -0.2794)
			(end 0.12065 -0.3048)
			(stroke
				(width 0.1)
				(type default)
			)
			(layer "F.Fab")
		)
		(fp_line
			(start 0.67945 -0.3048)
			(end 0.67945 0.3048)
			(stroke
				(width 0.1)
				(type default)
			)
			(layer "F.Fab")
		)
		(fp_line
			(start 0.67945 0.3048)
			(end 0.120396 0.3048)
			(stroke
				(width 0.1)
				(type default)
			)
			(layer "F.Fab")
		)
		(pad "1" smd circle
			(at -0.40005 0)
			(size 0 0)
			(layers "F.Cu" "F.Mask" "F.Paste")
			(net "PVCCIN_CPU1_LSET7")
		)
		(pad "2" smd circle
			(at 0.40005 0)
			(size 0 0)
			(layers "F.Cu" "F.Mask" "F.Paste")
			(net "GND")
		)
	)
	(footprint ""
		(layer "F.Cu")
		(at 189.28588 -126.964948 90)
		(property "Reference" "R1833"
			(at 0 0 90)
			(layer "F.SilkS")
			(hide yes)
			(effects
				(font
					(size 1.27 1.27)
				)
			)
		)
		(property "Value" ""
			(at 0 0 90)
			(layer "F.Fab")
			(effects
				(font
					(size 1.27 1.27)
				)
			)
		)
		(duplicate_pad_numbers_are_jumpers no)
		(fp_line
			(start 0.7874 -0.4064)
			(end 0.7874 0.4064)
			(stroke
				(width 0.1524)
				(type default)
			)
			(layer "F.SilkS")
		)
		(fp_line
			(start -0.7874 -0.4064)
			(end 0.7874 -0.4064)
			(stroke
				(width 0.1524)
				(type default)
			)
			(layer "F.SilkS")
		)
		(fp_line
			(start 0.7874 0.4064)
			(end -0.7874 0.4064)
			(stroke
				(width 0.1524)
				(type default)
			)
			(layer "F.SilkS")
		)
		(fp_line
			(start -0.7874 0.4064)
			(end -0.7874 -0.4064)
			(stroke
				(width 0.1524)
				(type default)
			)
			(layer "F.SilkS")
		)
		(fp_line
			(start -0.12065 -0.305054)
			(end -0.12065 -0.2794)
			(stroke
				(width 0.1)
				(type default)
			)
			(layer "F.Fab")
		)
		(fp_line
			(start -0.67945 -0.305054)
			(end -0.12065 -0.305054)
			(stroke
				(width 0.1)
				(type default)
			)
			(layer "F.Fab")
		)
		(fp_line
			(start 0.67945 -0.3048)
			(end 0.67945 0.3048)
			(stroke
				(width 0.1)
				(type default)
			)
			(layer "F.Fab")
		)
		(fp_line
			(start 0.12065 -0.3048)
			(end 0.67945 -0.3048)
			(stroke
				(width 0.1)
				(type default)
			)
			(layer "F.Fab")
		)
		(fp_line
			(start 0.12065 -0.2794)
			(end 0.12065 -0.3048)
			(stroke
				(width 0.1)
				(type default)
			)
			(layer "F.Fab")
		)
		(fp_line
			(start -0.12065 -0.2794)
			(end 0.12065 -0.2794)
			(stroke
				(width 0.1)
				(type default)
			)
			(layer "F.Fab")
		)
		(fp_line
			(start 0.120396 0.2794)
			(end -0.12065 0.2794)
			(stroke
				(width 0.1)
				(type default)
			)
			(layer "F.Fab")
		)
		(fp_line
			(start -0.12065 0.2794)
			(end -0.12065 0.3048)
			(stroke
				(width 0.1)
				(type default)
			)
			(layer "F.Fab")
		)
		(fp_line
			(start 0.67945 0.3048)
			(end 0.120396 0.3048)
			(stroke
				(width 0.1)
				(type default)
			)
			(layer "F.Fab")
		)
		(fp_line
			(start 0.120396 0.3048)
			(end 0.120396 0.2794)
			(stroke
				(width 0.1)
				(type default)
			)
			(layer "F.Fab")
		)
		(fp_line
			(start -0.12065 0.3048)
			(end -0.67945 0.3048)
			(stroke
				(width 0.1)
				(type default)
			)
			(layer "F.Fab")
		)
		(fp_line
			(start -0.67945 0.3048)
			(end -0.67945 -0.305054)
			(stroke
				(width 0.1)
				(type default)
			)
			(layer "F.Fab")
		)
		(pad "1" smd circle
			(at -0.40005 0 90)
			(size 0 0)
			(layers "F.Cu" "F.Mask" "F.Paste")
			(net "FM_JTAG_BMC_MUX_SEL_R")
		)
		(pad "2" smd circle
			(at 0.40005 0 90)
			(size 0 0)
			(layers "F.Cu" "F.Mask" "F.Paste")
			(net "FM_JTAG_BMC_MUX_SEL")
		)
	)
	(footprint ""
		(layer "F.Cu")
		(at 52.15128 -170.576748 -90)
		(property "Reference" "PC428"
			(at 0 0 270)
			(layer "F.SilkS")
			(hide yes)
			(effects
				(font
					(size 1.27 1.27)
				)
			)
		)
		(property "Value" ""
			(at 0 0 270)
			(layer "F.Fab")
			(effects
				(font
					(size 1.27 1.27)
				)
			)
		)
		(duplicate_pad_numbers_are_jumpers no)
		(fp_line
			(start -0.7874 0.4064)
			(end -0.7874 -0.4064)
			(stroke
				(width 0.1524)
				(type default)
			)
			(layer "F.SilkS")
		)
		(fp_line
			(start 0.7874 0.4064)
			(end -0.7874 0.4064)
			(stroke
				(width 0.1524)
				(type default)
			)
			(layer "F.SilkS")
		)
		(fp_line
			(start -0.7874 -0.4064)
			(end 0.7874 -0.4064)
			(stroke
				(width 0.1524)
				(type default)
			)
			(layer "F.SilkS")
		)
		(fp_line
			(start 0.7874 -0.4064)
			(end 0.7874 0.4064)
			(stroke
				(width 0.1524)
				(type default)
			)
			(layer "F.SilkS")
		)
		(fp_line
			(start -0.67945 0.3048)
			(end -0.67945 -0.305054)
			(stroke
				(width 0.1)
				(type default)
			)
			(layer "F.Fab")
		)
		(fp_line
			(start -0.12065 0.3048)
			(end -0.67945 0.3048)
			(stroke
				(width 0.1)
				(type default)
			)
			(layer "F.Fab")
		)
		(fp_line
			(start 0.120396 0.3048)
			(end 0.120396 0.2794)
			(stroke
				(width 0.1)
				(type default)
			)
			(layer "F.Fab")
		)
		(fp_line
			(start 0.67945 0.3048)
			(end 0.120396 0.3048)
			(stroke
				(width 0.1)
				(type default)
			)
			(layer "F.Fab")
		)
		(fp_line
			(start -0.12065 0.2794)
			(end -0.12065 0.3048)
			(stroke
				(width 0.1)
				(type default)
			)
			(layer "F.Fab")
		)
		(fp_line
			(start 0.120396 0.2794)
			(end -0.12065 0.2794)
			(stroke
				(width 0.1)
				(type default)
			)
			(layer "F.Fab")
		)
		(fp_line
			(start -0.12065 -0.2794)
			(end 0.12065 -0.2794)
			(stroke
				(width 0.1)
				(type default)
			)
			(layer "F.Fab")
		)
		(fp_line
			(start 0.12065 -0.2794)
			(end 0.12065 -0.3048)
			(stroke
				(width 0.1)
				(type default)
			)
			(layer "F.Fab")
		)
		(fp_line
			(start 0.12065 -0.3048)
			(end 0.67945 -0.3048)
			(stroke
				(width 0.1)
				(type default)
			)
			(layer "F.Fab")
		)
		(fp_line
			(start 0.67945 -0.3048)
			(end 0.67945 0.3048)
			(stroke
				(width 0.1)
				(type default)
			)
			(layer "F.Fab")
		)
		(fp_line
			(start -0.67945 -0.305054)
			(end -0.12065 -0.305054)
			(stroke
				(width 0.1)
				(type default)
			)
			(layer "F.Fab")
		)
		(fp_line
			(start -0.12065 -0.305054)
			(end -0.12065 -0.2794)
			(stroke
				(width 0.1)
				(type default)
			)
			(layer "F.Fab")
		)
		(pad "1" smd circle
			(at -0.40005 0 270)
			(size 0 0)
			(layers "F.Cu" "F.Mask" "F.Paste")
			(net "PVCCFA_EHV_CPU1_VDD1")
		)
		(pad "2" smd circle
			(at 0.40005 0 270)
			(size 0 0)
			(layers "F.Cu" "F.Mask" "F.Paste")
			(net "GND")
		)
	)
	(footprint ""
		(layer "F.Cu")
		(at 28.578048 -77.783944)
		(property "Reference" "R3143"
			(at 0 0 0)
			(layer "F.SilkS")
			(hide yes)
			(effects
				(font
					(size 1.27 1.27)
				)
			)
		)
		(property "Value" ""
			(at 0 0 0)
			(layer "F.Fab")
			(effects
				(font
					(size 1.27 1.27)
				)
			)
		)
		(duplicate_pad_numbers_are_jumpers no)
		(fp_line
			(start -0.7874 -0.4064)
			(end 0.7874 -0.4064)
			(stroke
				(width 0.1524)
				(type default)
			)
			(layer "F.SilkS")
		)
		(fp_line
			(start -0.7874 0.4064)
			(end -0.7874 -0.4064)
			(stroke
				(width 0.1524)
				(type default)
			)
			(layer "F.SilkS")
		)
		(fp_line
			(start 0.7874 -0.4064)
			(end 0.7874 0.4064)
			(stroke
				(width 0.1524)
				(type default)
			)
			(layer "F.SilkS")
		)
		(fp_line
			(start 0.7874 0.4064)
			(end -0.7874 0.4064)
			(stroke
				(width 0.1524)
				(type default)
			)
			(layer "F.SilkS")
		)
		(fp_line
			(start -0.67945 -0.305054)
			(end -0.12065 -0.305054)
			(stroke
				(width 0.1)
				(type default)
			)
			(layer "F.Fab")
		)
		(fp_line
			(start -0.67945 0.3048)
			(end -0.67945 -0.305054)
			(stroke
				(width 0.1)
				(type default)
			)
			(layer "F.Fab")
		)
		(fp_line
			(start -0.12065 -0.305054)
			(end -0.12065 -0.2794)
			(stroke
				(width 0.1)
				(type default)
			)
			(layer "F.Fab")
		)
		(fp_line
			(start -0.12065 -0.2794)
			(end 0.12065 -0.2794)
			(stroke
				(width 0.1)
				(type default)
			)
			(layer "F.Fab")
		)
		(fp_line
			(start -0.12065 0.2794)
			(end -0.12065 0.3048)
			(stroke
				(width 0.1)
				(type default)
			)
			(layer "F.Fab")
		)
		(fp_line
			(start -0.12065 0.3048)
			(end -0.67945 0.3048)
			(stroke
				(width 0.1)
				(type default)
			)
			(layer "F.Fab")
		)
		(fp_line
			(start 0.120396 0.2794)
			(end -0.12065 0.2794)
			(stroke
				(width 0.1)
				(type default)
			)
			(layer "F.Fab")
		)
		(fp_line
			(start 0.120396 0.3048)
			(end 0.120396 0.2794)
			(stroke
				(width 0.1)
				(type default)
			)
			(layer "F.Fab")
		)
		(fp_line
			(start 0.12065 -0.3048)
			(end 0.67945 -0.3048)
			(stroke
				(width 0.1)
				(type default)
			)
			(layer "F.Fab")
		)
		(fp_line
			(start 0.12065 -0.2794)
			(end 0.12065 -0.3048)
			(stroke
				(width 0.1)
				(type default)
			)
			(layer "F.Fab")
		)
		(fp_line
			(start 0.67945 -0.3048)
			(end 0.67945 0.3048)
			(stroke
				(width 0.1)
				(type default)
			)
			(layer "F.Fab")
		)
		(fp_line
			(start 0.67945 0.3048)
			(end 0.120396 0.3048)
			(stroke
				(width 0.1)
				(type default)
			)
			(layer "F.Fab")
		)
		(pad "1" smd circle
			(at -0.40005 0)
			(size 0 0)
			(layers "F.Cu" "F.Mask" "F.Paste")
			(net "HP_LVC3_OCP_V3_2_PRSNT2_N_R")
		)
		(pad "2" smd circle
			(at 0.40005 0)
			(size 0 0)
			(layers "F.Cu" "F.Mask" "F.Paste")
			(net "HP_LVC3_OCP_V3_2_ATTN_OUT_SW_N")
		)
	)
	(footprint ""
		(layer "F.Cu")
		(at 226.733608 -405.839422 180)
		(property "Reference" "PC2227"
			(at 0 0 180)
			(layer "F.SilkS")
			(hide yes)
			(effects
				(font
					(size 1.27 1.27)
				)
			)
		)
		(property "Value" ""
			(at 0 0 180)
			(layer "F.Fab")
			(effects
				(font
					(size 1.27 1.27)
				)
			)
		)
		(duplicate_pad_numbers_are_jumpers no)
		(fp_line
			(start 0.7874 0.4064)
			(end -0.7874 0.4064)
			(stroke
				(width 0.1524)
				(type default)
			)
			(layer "F.SilkS")
		)
		(fp_line
			(start 0.7874 -0.4064)
			(end 0.7874 0.4064)
			(stroke
				(width 0.1524)
				(type default)
			)
			(layer "F.SilkS")
		)
		(fp_line
			(start -0.7874 0.4064)
			(end -0.7874 -0.4064)
			(stroke
				(width 0.1524)
				(type default)
			)
			(layer "F.SilkS")
		)
		(fp_line
			(start -0.7874 -0.4064)
			(end 0.7874 -0.4064)
			(stroke
				(width 0.1524)
				(type default)
			)
			(layer "F.SilkS")
		)
		(fp_line
			(start 0.67945 0.3048)
			(end 0.120396 0.3048)
			(stroke
				(width 0.1)
				(type default)
			)
			(layer "F.Fab")
		)
		(fp_line
			(start 0.67945 -0.3048)
			(end 0.67945 0.3048)
			(stroke
				(width 0.1)
				(type default)
			)
			(layer "F.Fab")
		)
		(fp_line
			(start 0.12065 -0.2794)
			(end 0.12065 -0.3048)
			(stroke
				(width 0.1)
				(type default)
			)
			(layer "F.Fab")
		)
		(fp_line
			(start 0.12065 -0.3048)
			(end 0.67945 -0.3048)
			(stroke
				(width 0.1)
				(type default)
			)
			(layer "F.Fab")
		)
		(fp_line
			(start 0.120396 0.3048)
			(end 0.120396 0.2794)
			(stroke
				(width 0.1)
				(type default)
			)
			(layer "F.Fab")
		)
		(fp_line
			(start 0.120396 0.2794)
			(end -0.12065 0.2794)
			(stroke
				(width 0.1)
				(type default)
			)
			(layer "F.Fab")
		)
		(fp_line
			(start -0.12065 0.3048)
			(end -0.67945 0.3048)
			(stroke
				(width 0.1)
				(type default)
			)
			(layer "F.Fab")
		)
		(fp_line
			(start -0.12065 0.2794)
			(end -0.12065 0.3048)
			(stroke
				(width 0.1)
				(type default)
			)
			(layer "F.Fab")
		)
		(fp_line
			(start -0.12065 -0.2794)
			(end 0.12065 -0.2794)
			(stroke
				(width 0.1)
				(type default)
			)
			(layer "F.Fab")
		)
		(fp_line
			(start -0.12065 -0.305054)
			(end -0.12065 -0.2794)
			(stroke
				(width 0.1)
				(type default)
			)
			(layer "F.Fab")
		)
		(fp_line
			(start -0.67945 0.3048)
			(end -0.67945 -0.305054)
			(stroke
				(width 0.1)
				(type default)
			)
			(layer "F.Fab")
		)
		(fp_line
			(start -0.67945 -0.305054)
			(end -0.12065 -0.305054)
			(stroke
				(width 0.1)
				(type default)
			)
			(layer "F.Fab")
		)
		(pad "1" smd circle
			(at -0.40005 0 180)
			(size 0 0)
			(layers "F.Cu" "F.Mask" "F.Paste")
			(net "HSC_SS")
		)
		(pad "2" smd circle
			(at 0.40005 0 180)
			(size 0 0)
			(layers "F.Cu" "F.Mask" "F.Paste")
			(net "AGND_HSC")
		)
	)
)
